(kicad_pcb
	(version 20260206)
	(generator "pcbnew")
	(generator_version "10.0")
	(general
		(thickness 1.6)
		(legacy_teardrops no)
	)
	(paper "A4")
	(title_block
		(title "Bryce Canyon_IOM_M2_16342-2_OCP.brd")
		(comment 1 "Bryce Canyon / footprints 599-604 of 1146")
	)
	(layers
		(0 "F.Cu" signal "TOP")
		(4 "In1.Cu" signal "L2GND")
		(6 "In2.Cu" signal "L3")
		(8 "In3.Cu" signal "L4VCC")
		(10 "In4.Cu" signal "L5VCC")
		(12 "In5.Cu" signal "L6")
		(14 "In6.Cu" signal "L7GND")
		(2 "B.Cu" signal "BOTTOM")
		(9 "F.Adhes" user "F.Adhesive")
		(11 "B.Adhes" user "B.Adhesive")
		(13 "F.Paste" user "Package Geometry/Pastemask Top")
		(15 "B.Paste" user "Package Geometry/Pastemask Bottom")
		(5 "F.SilkS" user "Ref Des/Silkscreen Top")
		(7 "B.SilkS" user "Ref Des/Silkscreen Bottom")
		(1 "F.Mask" user "Board Geometry/Soldermask Top")
		(3 "B.Mask" user "Board Geometry/Soldermask Bottom")
		(17 "Dwgs.User" user "User.Drawings")
		(19 "Cmts.User" user "User.Comments")
		(21 "Eco1.User" user "User.Eco1")
		(23 "Eco2.User" user "User.Eco2")
		(25 "Edge.Cuts" user "Board Geometry/Outline")
		(27 "Margin" user)
		(31 "F.CrtYd" user "Package Geometry/Place Bound Top")
		(29 "B.CrtYd" user "Package Geometry/Place Bound Bottom")
		(35 "F.Fab" user "Ref Des/Assembly Top")
		(33 "B.Fab" user "Ref Des/Assembly Bottom")
	)
	(footprint ""
		(layer "F.Cu")
		(at 92.2528 -174.0408 -90)
		(property "Reference" "U107"
			(at 0 0 270)
			(layer "F.SilkS")
			(hide yes)
			(effects
				(font
					(size 1.27 1.27)
				)
			)
		)
		(property "Value" "SN74CBTLV3245APWR-GP"
			(at -0.889 -6.2738 270)
			(unlocked yes)
			(layer "F.Fab")
			(hide yes)
			(effects
				(font
					(size 1.016 1.016)
					(thickness 0.1524)
				)
			)
		)
		(property "Device Type" "TSOIC20H48"
			(at -0.9144 -7.8994 270)
			(unlocked yes)
			(layer "F.Fab")
			(hide yes)
			(effects
				(font
					(size 1.016 1.016)
					(thickness 0.1524)
				)
			)
		)
		(duplicate_pad_numbers_are_jumpers no)
		(fp_line
			(start -3.556 4.064)
			(end -3.556 1.778)
			(stroke
				(width 0.508)
				(type default)
			)
			(layer "F.SilkS")
		)
		(fp_line
			(start -3.556 1.397)
			(end -3.556 1.778)
			(stroke
				(width 0.2032)
				(type default)
			)
			(layer "F.SilkS")
		)
		(fp_line
			(start 3.175 1.397)
			(end -3.556 1.397)
			(stroke
				(width 0.2032)
				(type default)
			)
			(layer "F.SilkS")
		)
		(fp_line
			(start -2.667 0)
			(end -3.556 0.889)
			(stroke
				(width 0.2032)
				(type default)
			)
			(layer "F.SilkS")
		)
		(fp_line
			(start -2.667 0)
			(end -3.556 -0.889)
			(stroke
				(width 0.2032)
				(type default)
			)
			(layer "F.SilkS")
		)
		(fp_line
			(start -3.556 -1.397)
			(end -3.556 4.064)
			(stroke
				(width 0.2032)
				(type default)
			)
			(layer "F.SilkS")
		)
		(fp_line
			(start -3.556 -1.397)
			(end 3.175 -1.397)
			(stroke
				(width 0.2032)
				(type default)
			)
			(layer "F.SilkS")
		)
		(fp_line
			(start 3.175 -1.397)
			(end 3.175 1.397)
			(stroke
				(width 0.2032)
				(type default)
			)
			(layer "F.SilkS")
		)
		(fp_poly
			(pts
				(xy -3.25628 -1.8542) (xy 3.25628 -1.8542) (xy 3.25628 1.8542) (xy -3.25628 1.8542)
			)
			(stroke
				(width 0)
				(type default)
			)
			(fill yes)
			(layer "F.SilkS")
		)
		(fp_rect
			(start -3.556 3.81)
			(end 3.556 -3.81)
			(stroke
				(width 0)
				(type default)
			)
			(fill no)
			(layer "F.CrtYd")
		)
		(fp_poly
			(pts
				(xy -3.556 -3.81) (xy 3.556 -3.81) (xy 3.556 3.81) (xy -3.556 3.81)
			)
			(stroke
				(width 0)
				(type default)
			)
			(fill no)
			(layer "F.Fab")
		)
		(pad "1" smd rect
			(at -2.92608 2.8194 270)
			(size 0.3556 1.524)
			(layers "F.Cu" "F.Mask" "F.Paste")
			(net "Net_131")
		)
		(pad "2" smd rect
			(at -2.27584 2.8194 270)
			(size 0.3556 1.524)
			(layers "F.Cu" "F.Mask" "F.Paste")
			(net "Net_68")
		)
		(pad "3" smd rect
			(at -1.6256 2.8194 270)
			(size 0.3556 1.524)
			(layers "F.Cu" "F.Mask" "F.Paste")
			(net "Net_70")
		)
		(pad "4" smd rect
			(at -0.97536 2.8194 270)
			(size 0.3556 1.524)
			(layers "F.Cu" "F.Mask" "F.Paste")
			(net "Net_66")
		)
		(pad "5" smd rect
			(at -0.32512 2.8194 270)
			(size 0.3556 1.524)
			(layers "F.Cu" "F.Mask" "F.Paste")
			(net "I2C_DPB_MISC_SCL_OUT")
		)
		(pad "6" smd rect
			(at 0.32512 2.8194 270)
			(size 0.3556 1.524)
			(layers "F.Cu" "F.Mask" "F.Paste")
			(net "I2C_DPB_MISC_SDA_OUT")
		)
		(pad "7" smd rect
			(at 0.97536 2.8194 270)
			(size 0.3556 1.524)
			(layers "F.Cu" "F.Mask" "F.Paste")
			(net "DPB_MISC_ALERT")
		)
		(pad "8" smd rect
			(at 1.6256 2.8194 270)
			(size 0.3556 1.524)
			(layers "F.Cu" "F.Mask" "F.Paste")
			(net "Net_130")
		)
		(pad "9" smd rect
			(at 2.27584 2.8194 270)
			(size 0.3556 1.524)
			(layers "F.Cu" "F.Mask" "F.Paste")
			(net "Net_129")
		)
		(pad "10" smd rect
			(at 2.92608 2.8194 270)
			(size 0.3556 1.524)
			(layers "F.Cu" "F.Mask" "F.Paste")
			(net "GND")
		)
		(pad "11" smd rect
			(at 2.92608 -2.8194 270)
			(size 0.3556 1.524)
			(layers "F.Cu" "F.Mask" "F.Paste")
			(net "Net_128")
		)
		(pad "12" smd rect
			(at 2.27584 -2.8194 270)
			(size 0.3556 1.524)
			(layers "F.Cu" "F.Mask" "F.Paste")
			(net "Net_127")
		)
		(pad "13" smd rect
			(at 1.6256 -2.8194 270)
			(size 0.3556 1.524)
			(layers "F.Cu" "F.Mask" "F.Paste")
			(net "DPB_MISC_ALERT_OUT_R")
		)
		(pad "14" smd rect
			(at 0.97536 -2.8194 270)
			(size 0.3556 1.524)
			(layers "F.Cu" "F.Mask" "F.Paste")
			(net "I2C_DPB_MISC_SDA_R")
		)
		(pad "15" smd rect
			(at 0.32512 -2.8194 270)
			(size 0.3556 1.524)
			(layers "F.Cu" "F.Mask" "F.Paste")
			(net "I2C_DPB_MISC_SCL_R")
		)
		(pad "16" smd rect
			(at -0.32512 -2.8194 270)
			(size 0.3556 1.524)
			(layers "F.Cu" "F.Mask" "F.Paste")
			(net "Net_71")
		)
		(pad "17" smd rect
			(at -0.97536 -2.8194 270)
			(size 0.3556 1.524)
			(layers "F.Cu" "F.Mask" "F.Paste")
			(net "Net_69")
		)
		(pad "18" smd rect
			(at -1.6256 -2.8194 270)
			(size 0.3556 1.524)
			(layers "F.Cu" "F.Mask" "F.Paste")
			(net "Net_67")
		)
		(pad "19" smd rect
			(at -2.27584 -2.8194 270)
			(size 0.3556 1.524)
			(layers "F.Cu" "F.Mask" "F.Paste")
			(net "PWRGD_P3V3_STBY_N_R2")
		)
		(pad "20" smd rect
			(at -2.92608 -2.8194 270)
			(size 0.3556 1.524)
			(layers "F.Cu" "F.Mask" "F.Paste")
			(net "P3V3_STBY")
		)
	)
	(footprint ""
		(layer "F.Cu")
		(at 212.836506 -90.426032 -90)
		(property "Reference" "R820"
			(at 0 0 270)
			(layer "F.SilkS")
			(hide yes)
			(effects
				(font
					(size 1.27 1.27)
				)
			)
		)
		(property "Value" "0R2J-2-GP"
			(at 0.064008 -3.993896 270)
			(unlocked yes)
			(layer "F.Fab")
			(hide yes)
			(effects
				(font
					(size 1.016 1.016)
					(thickness 0.1524)
				)
			)
		)
		(property "Device Type" "R402H16"
			(at 0.064008 -5.517896 270)
			(unlocked yes)
			(layer "F.Fab")
			(hide yes)
			(effects
				(font
					(size 1.016 1.016)
					(thickness 0.1524)
				)
			)
		)
		(duplicate_pad_numbers_are_jumpers no)
		(fp_line
			(start -0.508 -0.9398)
			(end -0.508 0.9398)
			(stroke
				(width 0.1524)
				(type default)
			)
			(layer "F.SilkS")
		)
		(fp_line
			(start 0.508 -0.9398)
			(end -0.508 -0.9398)
			(stroke
				(width 0.1524)
				(type default)
			)
			(layer "F.SilkS")
		)
		(fp_rect
			(start -0.508 0.9398)
			(end 0.508 -0.9398)
			(stroke
				(width 0)
				(type default)
			)
			(fill no)
			(layer "F.CrtYd")
		)
		(fp_rect
			(start -0.508 0.9398)
			(end 0.508 -0.9398)
			(stroke
				(width 0)
				(type default)
			)
			(fill no)
			(layer "F.Fab")
		)
		(pad "1" smd custom
			(at 0 -0.4445 270)
			(size 0.1397 0.1397)
			(layers "F.Cu" "F.Mask" "F.Paste")
			(net "P3V3_M2_EN")
			(options
				(clearance outline)
				(anchor circle)
			)
			(primitives
				(gr_poly
					(pts
						(arc
							(start -0.1778 -0.2794)
							(mid -0.249642 -0.249642)
							(end -0.2794 -0.1778)
						)
						(arc
							(start -0.2794 0.1778)
							(mid -0.249642 0.249642)
							(end -0.1778 0.2794)
						)
						(arc
							(start 0.1778 0.2794)
							(mid 0.249642 0.249642)
							(end 0.2794 0.1778)
						)
						(arc
							(start 0.2794 -0.1778)
							(mid 0.249642 -0.249642)
							(end 0.1778 -0.2794)
						)
					)
					(width 0)
					(fill yes)
				)
			)
		)
		(pad "2" smd custom
			(at 0 0.4445 270)
			(size 0.1397 0.1397)
			(layers "F.Cu" "F.Mask" "F.Paste")
			(net "P3V3_PG")
			(options
				(clearance outline)
				(anchor circle)
			)
			(primitives
				(gr_poly
					(pts
						(arc
							(start -0.1778 -0.2794)
							(mid -0.249642 -0.249642)
							(end -0.2794 -0.1778)
						)
						(arc
							(start -0.2794 0.1778)
							(mid -0.249642 0.249642)
							(end -0.1778 0.2794)
						)
						(arc
							(start 0.1778 0.2794)
							(mid 0.249642 0.249642)
							(end 0.2794 0.1778)
						)
						(arc
							(start 0.2794 -0.1778)
							(mid 0.249642 -0.249642)
							(end 0.1778 -0.2794)
						)
					)
					(width 0)
					(fill yes)
				)
			)
		)
	)
	(footprint ""
		(layer "F.Cu")
		(at 86.368636 -29.238448)
		(property "Reference" "C22"
			(at 0 0 0)
			(layer "F.SilkS")
			(hide yes)
			(effects
				(font
					(size 1.27 1.27)
				)
			)
		)
		(property "Value" "SC1U16V3KX-5GP"
			(at 0 -2.8194 0)
			(unlocked yes)
			(layer "F.Fab")
			(hide yes)
			(effects
				(font
					(size 1.016 1.016)
					(thickness 0.1524)
				)
			)
		)
		(property "Device Type" "C603H36"
			(at 0 -4.3434 0)
			(unlocked yes)
			(layer "F.Fab")
			(hide yes)
			(effects
				(font
					(size 1.016 1.016)
					(thickness 0.1524)
				)
			)
		)
		(duplicate_pad_numbers_are_jumpers no)
		(fp_line
			(start 0.508 0)
			(end -0.508 0)
			(stroke
				(width 0.2032)
				(type default)
			)
			(layer "F.SilkS")
		)
		(fp_rect
			(start -0.5842 1.3335)
			(end 0.5842 -1.3335)
			(stroke
				(width 0)
				(type default)
			)
			(fill no)
			(layer "F.CrtYd")
		)
		(fp_rect
			(start -0.5842 1.3335)
			(end 0.5842 -1.3335)
			(stroke
				(width 0)
				(type default)
			)
			(fill no)
			(layer "F.Fab")
		)
		(pad "1" smd custom
			(at 0 -0.762)
			(size 0.2159 0.2159)
			(layers "F.Cu" "F.Mask" "F.Paste")
			(net "P5V_USB")
			(options
				(clearance outline)
				(anchor circle)
			)
			(primitives
				(gr_poly
					(pts
						(arc
							(start -0.3302 -0.4318)
							(mid -0.402042 -0.402042)
							(end -0.4318 -0.3302)
						)
						(arc
							(start -0.4318 0.3302)
							(mid -0.402042 0.402042)
							(end -0.3302 0.4318)
						)
						(arc
							(start 0.3302 0.4318)
							(mid 0.402042 0.402042)
							(end 0.4318 0.3302)
						)
						(arc
							(start 0.4318 -0.3302)
							(mid 0.402042 -0.402042)
							(end 0.3302 -0.4318)
						)
					)
					(width 0)
					(fill yes)
				)
			)
		)
		(pad "2" smd custom
			(at 0 0.762)
			(size 0.2159 0.2159)
			(layers "F.Cu" "F.Mask" "F.Paste")
			(net "GND")
			(options
				(clearance outline)
				(anchor circle)
			)
			(primitives
				(gr_poly
					(pts
						(arc
							(start -0.3302 -0.4318)
							(mid -0.402042 -0.402042)
							(end -0.4318 -0.3302)
						)
						(arc
							(start -0.4318 0.3302)
							(mid -0.402042 0.402042)
							(end -0.3302 0.4318)
						)
						(arc
							(start 0.3302 0.4318)
							(mid 0.402042 0.402042)
							(end 0.4318 0.3302)
						)
						(arc
							(start 0.4318 -0.3302)
							(mid 0.402042 -0.402042)
							(end 0.3302 -0.4318)
						)
					)
					(width 0)
					(fill yes)
				)
			)
		)
	)
	(footprint ""
		(layer "F.Cu")
		(at 80.552544 -168.199816 180)
		(property "Reference" "C243"
			(at 0 0 180)
			(layer "F.SilkS")
			(hide yes)
			(effects
				(font
					(size 1.27 1.27)
				)
			)
		)
		(property "Value" "SC10U6D3V5KX-4GP"
			(at -0.0762 -6.1214 180)
			(unlocked yes)
			(layer "F.Fab")
			(hide yes)
			(effects
				(font
					(size 1.016 1.016)
					(thickness 0.1524)
				)
			)
		)
		(property "Device Type" "C805H58"
			(at -0.0762 -8.1534 180)
			(unlocked yes)
			(layer "F.Fab")
			(hide yes)
			(effects
				(font
					(size 1.016 1.016)
					(thickness 0.1524)
				)
			)
		)
		(duplicate_pad_numbers_are_jumpers no)
		(fp_line
			(start 0.635 0)
			(end -0.635 0)
			(stroke
				(width 0.508)
				(type default)
			)
			(layer "F.SilkS")
		)
		(fp_rect
			(start -0.9652 1.778)
			(end 0.9652 -1.778)
			(stroke
				(width 0)
				(type default)
			)
			(fill no)
			(layer "F.CrtYd")
		)
		(fp_poly
			(pts
				(xy -0.9652 -1.778) (xy 0.9652 -1.778) (xy 0.9652 1.778) (xy -0.9652 1.778)
			)
			(stroke
				(width 0)
				(type default)
			)
			(fill no)
			(layer "F.Fab")
		)
		(pad "1" smd rect
			(at 0 -0.9652 180)
			(size 1.397 1.143)
			(layers "F.Cu" "F.Mask" "F.Paste")
			(net "P1V8_STBY")
		)
		(pad "2" smd rect
			(at 0 0.9652 180)
			(size 1.397 1.143)
			(layers "F.Cu" "F.Mask" "F.Paste")
			(net "GND")
		)
	)
	(footprint ""
		(layer "F.Cu")
		(at 56.3626 -158.8516)
		(property "Reference" "R395"
			(at 0 0 0)
			(layer "F.SilkS")
			(hide yes)
			(effects
				(font
					(size 1.27 1.27)
				)
			)
		)
		(property "Value" "4K7R2F-GP"
			(at 0.064008 -3.993896 0)
			(unlocked yes)
			(layer "F.Fab")
			(hide yes)
			(effects
				(font
					(size 1.016 1.016)
					(thickness 0.1524)
				)
			)
		)
		(property "Device Type" "R402H16"
			(at 0.064008 -5.517896 0)
			(unlocked yes)
			(layer "F.Fab")
			(hide yes)
			(effects
				(font
					(size 1.016 1.016)
					(thickness 0.1524)
				)
			)
		)
		(duplicate_pad_numbers_are_jumpers no)
		(fp_line
			(start -0.508 -0.9398)
			(end -0.508 0.9398)
			(stroke
				(width 0.1524)
				(type default)
			)
			(layer "F.SilkS")
		)
		(fp_line
			(start 0.508 -0.9398)
			(end -0.508 -0.9398)
			(stroke
				(width 0.1524)
				(type default)
			)
			(layer "F.SilkS")
		)
		(fp_rect
			(start -0.508 0.9398)
			(end 0.508 -0.9398)
			(stroke
				(width 0)
				(type default)
			)
			(fill no)
			(layer "F.CrtYd")
		)
		(fp_rect
			(start -0.508 0.9398)
			(end 0.508 -0.9398)
			(stroke
				(width 0)
				(type default)
			)
			(fill no)
			(layer "F.Fab")
		)
		(pad "1" smd custom
			(at 0 -0.4445)
			(size 0.1397 0.1397)
			(layers "F.Cu" "F.Mask" "F.Paste")
			(net "GND")
			(options
				(clearance outline)
				(anchor circle)
			)
			(primitives
				(gr_poly
					(pts
						(arc
							(start -0.1778 -0.2794)
							(mid -0.249642 -0.249642)
							(end -0.2794 -0.1778)
						)
						(arc
							(start -0.2794 0.1778)
							(mid -0.249642 0.249642)
							(end -0.1778 0.2794)
						)
						(arc
							(start 0.1778 0.2794)
							(mid 0.249642 0.249642)
							(end 0.2794 0.1778)
						)
						(arc
							(start 0.2794 -0.1778)
							(mid 0.249642 -0.249642)
							(end 0.1778 -0.2794)
						)
					)
					(width 0)
					(fill yes)
				)
			)
		)
		(pad "2" smd custom
			(at 0 0.4445)
			(size 0.1397 0.1397)
			(layers "F.Cu" "F.Mask" "F.Paste")
			(net "MAC2_TXCTL")
			(options
				(clearance outline)
				(anchor circle)
			)
			(primitives
				(gr_poly
					(pts
						(arc
							(start -0.1778 -0.2794)
							(mid -0.249642 -0.249642)
							(end -0.2794 -0.1778)
						)
						(arc
							(start -0.2794 0.1778)
							(mid -0.249642 0.249642)
							(end -0.1778 0.2794)
						)
						(arc
							(start 0.1778 0.2794)
							(mid 0.249642 0.249642)
							(end 0.2794 0.1778)
						)
						(arc
							(start 0.2794 -0.1778)
							(mid 0.249642 -0.249642)
							(end 0.1778 -0.2794)
						)
					)
					(width 0)
					(fill yes)
				)
			)
		)
	)
	(footprint ""
		(layer "F.Cu")
		(at 82.423 -136.017 180)
		(property "Reference" "R95"
			(at 0 0 180)
			(layer "F.SilkS")
			(hide yes)
			(effects
				(font
					(size 1.27 1.27)
				)
			)
		)
		(property "Value" "0R2J-2-GP"
			(at 0.064008 -3.993896 180)
			(unlocked yes)
			(layer "F.Fab")
			(hide yes)
			(effects
				(font
					(size 1.016 1.016)
					(thickness 0.1524)
				)
			)
		)
		(property "Device Type" "R402H16"
			(at 0.064008 -5.517896 180)
			(unlocked yes)
			(layer "F.Fab")
			(hide yes)
			(effects
				(font
					(size 1.016 1.016)
					(thickness 0.1524)
				)
			)
		)
		(duplicate_pad_numbers_are_jumpers no)
		(fp_line
			(start 0.508 -0.9398)
			(end -0.508 -0.9398)
			(stroke
				(width 0.1524)
				(type default)
			)
			(layer "F.SilkS")
		)
		(fp_line
			(start -0.508 -0.9398)
			(end -0.508 0.9398)
			(stroke
				(width 0.1524)
				(type default)
			)
			(layer "F.SilkS")
		)
		(fp_rect
			(start -0.508 0.9398)
			(end 0.508 -0.9398)
			(stroke
				(width 0)
				(type default)
			)
			(fill no)
			(layer "F.CrtYd")
		)
		(fp_rect
			(start -0.508 0.9398)
			(end 0.508 -0.9398)
			(stroke
				(width 0)
				(type default)
			)
			(fill no)
			(layer "F.Fab")
		)
		(pad "1" smd custom
			(at 0 -0.4445 180)
			(size 0.1397 0.1397)
			(layers "F.Cu" "F.Mask" "F.Paste")
			(net "UART_SEL_MUX")
			(options
				(clearance outline)
				(anchor circle)
			)
			(primitives
				(gr_poly
					(pts
						(arc
							(start -0.1778 -0.2794)
							(mid -0.249642 -0.249642)
							(end -0.2794 -0.1778)
						)
						(arc
							(start -0.2794 0.1778)
							(mid -0.249642 0.249642)
							(end -0.1778 0.2794)
						)
						(arc
							(start 0.1778 0.2794)
							(mid 0.249642 0.249642)
							(end 0.2794 0.1778)
						)
						(arc
							(start 0.2794 -0.1778)
							(mid 0.249642 -0.249642)
							(end 0.1778 -0.2794)
						)
					)
					(width 0)
					(fill yes)
				)
			)
		)
		(pad "2" smd custom
			(at 0 0.4445 180)
			(size 0.1397 0.1397)
			(layers "F.Cu" "F.Mask" "F.Paste")
			(net "D_FLIP_Q#")
			(options
				(clearance outline)
				(anchor circle)
			)
			(primitives
				(gr_poly
					(pts
						(arc
							(start -0.1778 -0.2794)
							(mid -0.249642 -0.249642)
							(end -0.2794 -0.1778)
						)
						(arc
							(start -0.2794 0.1778)
							(mid -0.249642 0.249642)
							(end -0.1778 0.2794)
						)
						(arc
							(start 0.1778 0.2794)
							(mid 0.249642 0.249642)
							(end 0.2794 0.1778)
						)
						(arc
							(start 0.2794 -0.1778)
							(mid 0.249642 -0.249642)
							(end 0.1778 -0.2794)
						)
					)
					(width 0)
					(fill yes)
				)
			)
		)
	)
)
